FILE_TYPE = MACRO_DRAWING;
SET COLOR_WIRE YELLOW;
SET COLOR_PROP ORANGE;
SET COLOR_DOT WHITE;
SET COLOR_ARC YELLOW;
SET COLOR_BODY GREEN;
SET COLOR_NOTE PURPLE;
SET PROP_DISPLAY VALUE;
SET PAGE_NUMBER P243;
FORCEADD VCC15..1
(-4675 14225);
FORCEPROP 3 LASTPIN (-4675 14175) SIG_NAME P1V8_PCH_AUX\g
J 0
(-4665 14185);
DISPLAY 0.659574 (-4665 14185);
PAINT MONO (-4665 14185);
DISPLAY INVISIBLE (-4665 14185);
FORCEPROP 1 LAST HDL_POWER P1V8_PCH_AUX
J 1
(-4675 14275);
DISPLAY 0.617021 (-4675 14275);
PAINT GREEN (-4675 14275);
FORCEPROP 1 LAST PATH I1
J 0
(-4625 14250);
DISPLAY 0.872340 (-4625 14250);
PAINT AQUA (-4625 14250);
DISPLAY INVISIBLE (-4625 14250);
FORCEPROP 2 LAST BOM_COST VR_SYSTEM 
J 0
(-4675 14325);
DISPLAY 0.680851 (-4675 14325);
DISPLAY INVISIBLE (-4675 14325);
FORCEPROP 2 LAST CDS_LIB logical_power
J 0
(-4675 14225);
DISPLAY INVISIBLE (-4675 14225);
FORCEADD UNIVERSAL_GND..1
(-4000 12125);
FORCEPROP 3 LASTPIN (-4000 12175) SIG_NAME GND\g
J 0
(-3990 12185);
DISPLAY 0.659574 (-3990 12185);
PAINT MONO (-3990 12185);
DISPLAY INVISIBLE (-3990 12185);
FORCEPROP 1 LAST PATH I11
J 0
(-3925 12125);
DISPLAY 0.872340 (-3925 12125);
PAINT AQUA (-3925 12125);
DISPLAY INVISIBLE (-3925 12125);
FORCEPROP 1 LAST HDL_POWER GND
J 1
(-3975 12050);
DISPLAY 0.872340 (-3975 12050);
PAINT GREEN (-3975 12050);
DISPLAY INVISIBLE (-3975 12050);
FORCEPROP 2 LAST CDS_LIB logical_power
J 0
(-4000 12125);
PAINT MONO (-4000 12125);
DISPLAY INVISIBLE (-4000 12125);
FORCEADD UNIVERSAL_POWER..1
(-4125 11725);
FORCEPROP 3 LASTPIN (-4125 11675) SIG_NAME P3V3_AUX\g
J 0
(-4115 11685);
DISPLAY 0.659574 (-4115 11685);
PAINT MONO (-4115 11685);
DISPLAY INVISIBLE (-4115 11685);
FORCEPROP 1 LAST HDL_POWER P3V3_AUX
J 1
(-4125 11775);
DISPLAY 0.617021 (-4125 11775);
PAINT GREEN (-4125 11775);
FORCEPROP 1 LAST PATH I12
J 0
(-4075 11750);
DISPLAY 0.872340 (-4075 11750);
PAINT AQUA (-4075 11750);
DISPLAY INVISIBLE (-4075 11750);
FORCEPROP 2 LAST BOM_COST VR_SYSTEM 
J 0
(-4125 11825);
DISPLAY 0.680851 (-4125 11825);
DISPLAY INVISIBLE (-4125 11825);
FORCEPROP 2 LAST CDS_LIB logical_power
J 0
(-4125 11725);
DISPLAY INVISIBLE (-4125 11725);
FORCEADD Q_RES..2
(-4675 11800);
FORCEPROP 1 LAST PART_NUMBER CS00004JA05
J 0
(-4635 11675);
DISPLAY 0.510638 (-4635 11675);
DISPLAY INVISIBLE (-4635 11675);
FORCEPROP 1 LAST VALUE 0
J 0
(-4630 11875);
DISPLAY 0.510638 (-4630 11875);
FORCEPROP 1 LAST TOLERANCE 5%
J 0
(-4630 11825);
DISPLAY 0.510638 (-4630 11825);
FORCEPROP 1 LAST WATTAGE 1/8W
J 0
(-4635 11775);
DISPLAY 0.510638 (-4635 11775);
FORCEPROP 1 LAST PACK_TYPE 0805LF
J 0
(-4635 11625);
DISPLAY 0.510638 (-4635 11625);
FORCEPROP 1 LAST MATERIAL EMPTY
J 0
(-4635 11725);
DISPLAY 0.510638 (-4635 11725);
PAINT RED (-4635 11725);
FORCEPROP 1 LAST $LOCATION R1765
J 0
(-4630 11925);
DISPLAY 0.510638 (-4630 11925);
FORCEPROP 1 LASTPIN (-4675 11900) $PN 1
J 0
(-4670 11862);
DISPLAY 0.787234 (-4670 11862);
PAINT MONO (-4670 11862);
FORCEPROP 1 LASTPIN (-4675 11700) $PN 2
J 0
(-4670 11710);
DISPLAY 0.787234 (-4670 11710);
PAINT MONO (-4670 11710);
FORCEPROP 1 LAST PATH I13
J 0
(-4625 11975);
DISPLAY 0.978723 (-4625 11975);
PAINT WHITE (-4625 11975);
DISPLAY INVISIBLE (-4625 11975);
FORCEPROP 2 LAST CDS_LIB pure_quanta
J 0
(-4675 11800);
DISPLAY INVISIBLE (-4675 11800);
FORCEPROP 0 LAST CDS_LOCATION R1765
J 0
(-4625 11950);
DISPLAY 1.021277 (-4625 11950);
DISPLAY INVISIBLE (-4625 11950);
FORCEPROP 0 LAST $SEC 1
J 0
(-4625 11950);
DISPLAY 0.680851 (-4625 11950);
PAINT MONO (-4625 11950);
DISPLAY INVISIBLE (-4625 11950);
FORCEPROP 0 LAST CDS_SEC 1
J 0
(-4625 11950);
DISPLAY 1.021277 (-4625 11950);
DISPLAY INVISIBLE (-4625 11950);
FORCEADD OFFPAGE..5
(-10200 12950);
FORCEPROP 2 LAST $XR0 240 
J 0
(-10485 12950);
DISPLAY 0.638298 (-10485 12950);
PAINT MONO (-10485 12950);
FORCEPROP 2 LAST CDS_LIB standard
J 0
(-10200 12950);
DISPLAY INVISIBLE (-10200 12950);
FORCEPROP 2 LAST PATH I14
J 0
(-10475 13000);
DISPLAY 1.021277 (-10475 13000);
DISPLAY INVISIBLE (-10475 13000);
FORCEPROP 1 LAST COMMENT_BODY TRUE
J 0
(-10100 12875);
DISPLAY 0.872340 (-10100 12875);
PAINT PEACH (-10100 12875);
DISPLAY INVISIBLE (-10100 12875);
FORCEPROP 1 LAST OFFPAGE TRUE
J 0
(-9875 12825);
DISPLAY 0.872340 (-9875 12825);
PAINT GREEN (-9875 12825);
DISPLAY INVISIBLE (-9875 12825);
FORCEADD MOSFET_N..1
R 2
(-8450 12800);
FORCEPROP 1 LAST PART_NUMBER BAM138K0000
J 2
(-8075 12330);
DISPLAY 0.723404 (-8075 12330);
PAINT GREEN (-8075 12330);
DISPLAY INVISIBLE (-8075 12330);
FORCEPROP 2 LAST MANUF_PN BSS138K
J 2
(-8078 12594);
DISPLAY 1.021277 (-8078 12594);
FORCEPROP 2 LAST PATH I15
J 2
(-8078 12544);
DISPLAY 1.021277 (-8078 12544);
FORCEPROP 1 LAST VALUE BSS138K
J 2
(-8075 12490);
DISPLAY 0.723404 (-8075 12490);
PAINT GREEN (-8075 12490);
FORCEPROP 1 LAST MATERIAL IC
J 2
(-8075 12250);
DISPLAY 0.723404 (-8075 12250);
PAINT GREEN (-8075 12250);
FORCEPROP 1 LAST $LOCATION U307
J 2
(-8075 12410);
DISPLAY 0.723404 (-8075 12410);
PAINT GREEN (-8075 12410);
FORCEPROP 1 LASTPIN (-8500 12900) $PN D
R 1
J 0
(-8500 12893);
DISPLAY 0.659574 (-8500 12893);
PAINT MONO (-8500 12893);
FORCEPROP 1 LASTPIN (-8350 12700) $PN G
J 0
(-8360 12703);
DISPLAY 0.659574 (-8360 12703);
PAINT MONO (-8360 12703);
FORCEPROP 1 LASTPIN (-8500 12600) $PN S
R 1
J 2
(-8500 12613);
DISPLAY 0.659574 (-8500 12613);
PAINT MONO (-8500 12613);
FORCEPROP 1 LAST CDS_LMAN_SYM_OUTLINE -50,50,100,-150
J 2
(-8450 12800);
DISPLAY 0.468085 (-8450 12800);
PAINT GREEN (-8450 12800);
DISPLAY INVISIBLE (-8450 12800);
FORCEPROP 2 LAST CDS_LIB pure_quanta
J 2
(-8450 12800);
DISPLAY INVISIBLE (-8450 12800);
FORCEPROP 1 LAST PACK_TYPE SMLF
J 2
(-8475 12550);
DISPLAY 0.723404 (-8475 12550);
PAINT GREEN (-8475 12550);
DISPLAY INVISIBLE (-8475 12550);
FORCEPROP 0 LAST CDS_LOCATION U307
J 0
(-8075 12650);
DISPLAY 1.021277 (-8075 12650);
DISPLAY INVISIBLE (-8075 12650);
FORCEPROP 0 LAST $SEC 1
J 0
(-8075 12650);
DISPLAY 0.680851 (-8075 12650);
PAINT MONO (-8075 12650);
DISPLAY INVISIBLE (-8075 12650);
FORCEPROP 0 LAST CDS_SEC 1
J 0
(-8075 12650);
DISPLAY 1.021277 (-8075 12650);
DISPLAY INVISIBLE (-8075 12650);
FORCEADD Q_RES..2
(-8500 13250);
FORCEPROP 1 LAST PART_NUMBER CS31002FB08
J 0
(-8460 13125);
DISPLAY 0.638298 (-8460 13125);
DISPLAY INVISIBLE (-8460 13125);
FORCEPROP 1 LAST TOLERANCE 1%
J 0
(-8455 13275);
DISPLAY 0.638298 (-8455 13275);
FORCEPROP 1 LAST PACK_TYPE 0402LF
J 0
(-8460 13075);
DISPLAY 0.638298 (-8460 13075);
FORCEPROP 1 LAST MATERIAL CHIP
J 0
(-8460 13175);
DISPLAY 0.638298 (-8460 13175);
FORCEPROP 1 LAST WATTAGE 1/16W
J 0
(-8460 13225);
DISPLAY 0.638298 (-8460 13225);
FORCEPROP 1 LAST VALUE 10K
J 0
(-8455 13325);
DISPLAY 0.638298 (-8455 13325);
FORCEPROP 1 LAST $LOCATION R4176
J 0
(-8455 13375);
DISPLAY 0.638298 (-8455 13375);
FORCEPROP 1 LASTPIN (-8500 13350) $PN 1
J 0
(-8495 13312);
DISPLAY 0.787234 (-8495 13312);
PAINT MONO (-8495 13312);
FORCEPROP 1 LASTPIN (-8500 13150) $PN 2
J 0
(-8495 13160);
DISPLAY 0.787234 (-8495 13160);
PAINT MONO (-8495 13160);
FORCEPROP 1 LAST PATH I16
J 0
(-8450 13425);
DISPLAY 0.978723 (-8450 13425);
PAINT WHITE (-8450 13425);
DISPLAY INVISIBLE (-8450 13425);
FORCEPROP 2 LAST CDS_LIB pure_quanta
J 0
(-8500 13250);
DISPLAY INVISIBLE (-8500 13250);
FORCEPROP 2 LAST CDS_LOCATION R4176
J 0
(-8450 13475);
DISPLAY 1.021277 (-8450 13475);
DISPLAY INVISIBLE (-8450 13475);
FORCEPROP 0 LAST $SEC 1
J 0
(-8450 13425);
DISPLAY 0.680851 (-8450 13425);
PAINT MONO (-8450 13425);
DISPLAY INVISIBLE (-8450 13425);
FORCEPROP 2 LAST CDS_SEC 1
J 0
(-8450 13475);
DISPLAY 1.021277 (-8450 13475);
DISPLAY INVISIBLE (-8450 13475);
FORCEADD UNIVERSAL_POWER..1
(-8500 13550);
FORCEPROP 3 LASTPIN (-8500 13500) SIG_NAME P3V3_AUX\g
J 0
(-8490 13510);
DISPLAY 0.659574 (-8490 13510);
PAINT MONO (-8490 13510);
DISPLAY INVISIBLE (-8490 13510);
FORCEPROP 1 LAST HDL_POWER P3V3_AUX
J 1
(-8500 13600);
DISPLAY 0.617021 (-8500 13600);
PAINT GREEN (-8500 13600);
FORCEPROP 2 LAST CDS_LIB logical_power
J 0
(-8500 13550);
DISPLAY INVISIBLE (-8500 13550);
FORCEPROP 1 LAST PATH I17
J 0
(-8450 13575);
DISPLAY 0.872340 (-8450 13575);
PAINT AQUA (-8450 13575);
DISPLAY INVISIBLE (-8450 13575);
FORCEPROP 2 LAST BOM_COST VR_SYSTEM 
J 0
(-8500 13650);
DISPLAY 0.680851 (-8500 13650);
DISPLAY INVISIBLE (-8500 13650);
FORCEADD UNIVERSAL_GND..1
(-8500 12350);
FORCEPROP 3 LASTPIN (-8500 12400) SIG_NAME GND\g
J 0
(-8490 12410);
DISPLAY 0.659574 (-8490 12410);
PAINT MONO (-8490 12410);
DISPLAY INVISIBLE (-8490 12410);
FORCEPROP 2 LAST CDS_LIB logical_power
J 0
(-8500 12350);
DISPLAY INVISIBLE (-8500 12350);
FORCEPROP 1 LAST PATH I18
J 0
(-8425 12350);
DISPLAY 0.872340 (-8425 12350);
PAINT AQUA (-8425 12350);
DISPLAY INVISIBLE (-8425 12350);
FORCEPROP 1 LAST HDL_POWER GND
J 1
(-8475 12275);
DISPLAY 0.872340 (-8475 12275);
PAINT GREEN (-8475 12275);
DISPLAY INVISIBLE (-8475 12275);
FORCEADD Q_RES..1
(-7375 12700);
FORCEPROP 1 LAST PART_NUMBER CS00002JB13
J 0
(-7450 12650);
DISPLAY 0.319149 (-7450 12650);
DISPLAY INVISIBLE (-7450 12650);
FORCEPROP 1 LAST MATERIAL CHIP
J 0
(-7150 12700);
DISPLAY 0.404255 (-7150 12700);
FORCEPROP 1 LAST VALUE 0
J 2
(-7225 12700);
DISPLAY 0.404255 (-7225 12700);
FORCEPROP 1 LAST TOLERANCE 5%
J 0
(-7200 12700);
DISPLAY 0.404255 (-7200 12700);
FORCEPROP 1 LAST $LOCATION R4177
J 0
(-7600 12700);
DISPLAY 0.638298 (-7600 12700);
FORCEPROP 1 LASTPIN (-7475 12700) $PN 1
J 0
(-7463 12712);
DISPLAY 0.787234 (-7463 12712);
PAINT MONO (-7463 12712);
FORCEPROP 1 LASTPIN (-7275 12700) $PN 2
J 0
(-7313 12712);
DISPLAY 0.787234 (-7313 12712);
PAINT MONO (-7313 12712);
FORCEPROP 1 LAST WATTAGE 1/16W
J 2
(-7275 12625);
DISPLAY 0.319149 (-7275 12625);
DISPLAY INVISIBLE (-7275 12625);
FORCEPROP 1 LAST PACK_TYPE 0402LF
J 0
(-7125 12700);
DISPLAY 0.510638 (-7125 12700);
DISPLAY INVISIBLE (-7125 12700);
FORCEPROP 1 LAST PATH I19
J 0
(-7425 12850);
DISPLAY 0.978723 (-7425 12850);
PAINT WHITE (-7425 12850);
DISPLAY INVISIBLE (-7425 12850);
FORCEPROP 2 LAST CDS_LIB pure_quanta
J 0
(-7375 12700);
DISPLAY INVISIBLE (-7375 12700);
FORCEPROP 0 LAST CDS_LOCATION R4177
J 0
(-7525 12750);
DISPLAY 1.021277 (-7525 12750);
DISPLAY INVISIBLE (-7525 12750);
FORCEPROP 0 LAST $SEC 1
J 0
(-7525 12750);
DISPLAY 0.680851 (-7525 12750);
PAINT MONO (-7525 12750);
DISPLAY INVISIBLE (-7525 12750);
FORCEPROP 0 LAST CDS_SEC 1
J 0
(-7525 12750);
DISPLAY 1.021277 (-7525 12750);
DISPLAY INVISIBLE (-7525 12750);
FORCEADD Q_RES..2
(-4675 13625);
FORCEPROP 1 LAST PART_NUMBER CS00004JA05
J 0
(-4635 13500);
DISPLAY 0.510638 (-4635 13500);
DISPLAY INVISIBLE (-4635 13500);
FORCEPROP 1 LAST PACK_TYPE 0805LF
J 0
(-4635 13450);
DISPLAY 0.510638 (-4635 13450);
FORCEPROP 1 LAST TOLERANCE 5%
J 0
(-4630 13650);
DISPLAY 0.510638 (-4630 13650);
FORCEPROP 1 LAST MATERIAL CHIP
J 0
(-4635 13550);
DISPLAY 0.510638 (-4635 13550);
FORCEPROP 1 LAST WATTAGE 1/8W
J 0
(-4635 13600);
DISPLAY 0.510638 (-4635 13600);
FORCEPROP 1 LAST VALUE 0
J 0
(-4630 13700);
DISPLAY 0.510638 (-4630 13700);
FORCEPROP 1 LAST $LOCATION R1747
J 0
(-4630 13750);
DISPLAY 0.510638 (-4630 13750);
FORCEPROP 1 LASTPIN (-4675 13725) $PN 1
J 0
(-4670 13687);
DISPLAY 0.787234 (-4670 13687);
PAINT MONO (-4670 13687);
FORCEPROP 1 LASTPIN (-4675 13525) $PN 2
J 0
(-4670 13535);
DISPLAY 0.787234 (-4670 13535);
PAINT MONO (-4670 13535);
FORCEPROP 1 LAST PATH I2
J 0
(-4625 13800);
DISPLAY 0.978723 (-4625 13800);
PAINT WHITE (-4625 13800);
DISPLAY INVISIBLE (-4625 13800);
FORCEPROP 2 LAST CDS_LIB pure_quanta
J 0
(-4675 13625);
DISPLAY INVISIBLE (-4675 13625);
FORCEPROP 0 LAST CDS_LOCATION R1747
J 0
(-4625 13775);
DISPLAY 1.021277 (-4625 13775);
DISPLAY INVISIBLE (-4625 13775);
FORCEPROP 0 LAST $SEC 1
J 0
(-4625 13775);
DISPLAY 0.680851 (-4625 13775);
PAINT MONO (-4625 13775);
DISPLAY INVISIBLE (-4625 13775);
FORCEPROP 0 LAST CDS_SEC 1
J 0
(-4625 13775);
DISPLAY 1.021277 (-4625 13775);
DISPLAY INVISIBLE (-4625 13775);
FORCEADD OFFPAGE..1
R 2
(-6400 12700);
FORCEPROP 2 LAST $XR0 202 
J 0
(-6214 12700);
DISPLAY 0.638298 (-6214 12700);
PAINT MONO (-6214 12700);
FORCEPROP 1 LAST COMMENT_BODY TRUE
J 2
(-6525 12600);
DISPLAY 0.872340 (-6525 12600);
PAINT GREEN (-6525 12600);
DISPLAY INVISIBLE (-6525 12600);
FORCEPROP 1 LAST OFFPAGE TRUE
J 2
(-6725 12575);
DISPLAY 0.872340 (-6725 12575);
PAINT AQUA (-6725 12575);
DISPLAY INVISIBLE (-6725 12575);
FORCEPROP 2 LAST PATH I20
J 2
(-6450 12775);
DISPLAY 1.021277 (-6450 12775);
DISPLAY INVISIBLE (-6450 12775);
FORCEPROP 2 LAST CDS_LIB standard
J 2
(-6400 12700);
DISPLAY INVISIBLE (-6400 12700);
FORCEADD UNIVERSAL_POWER..1
(-4000 12825);
FORCEPROP 3 LASTPIN (-4000 12775) SIG_NAME PGPPA_AUX\g
J 0
(-3990 12785);
DISPLAY 0.659574 (-3990 12785);
PAINT MONO (-3990 12785);
DISPLAY INVISIBLE (-3990 12785);
FORCEPROP 1 LAST HDL_POWER PGPPA_AUX
J 1
(-4000 12875);
DISPLAY 0.617021 (-4000 12875);
PAINT GREEN (-4000 12875);
FORCEPROP 1 LAST PATH I3
J 0
(-3950 12850);
DISPLAY 0.872340 (-3950 12850);
PAINT AQUA (-3950 12850);
DISPLAY INVISIBLE (-3950 12850);
FORCEPROP 2 LAST CDS_LIB logical_power
J 0
(-4000 12825);
DISPLAY INVISIBLE (-4000 12825);
FORCEPROP 2 LAST BOM_COST VR_SYSTEM 
J 0
(-4000 12925);
DISPLAY 0.680851 (-4000 12925);
DISPLAY INVISIBLE (-4000 12925);
FORCEADD Q_CAP..1
(-4000 12450);
FORCEPROP 1 LAST PART_NUMBER CH6223MEA01
J 0
(-3950 12300);
DISPLAY 0.787234 (-3950 12300);
DISPLAY INVISIBLE (-3950 12300);
FORCEPROP 1 LAST MATERIAL X6S
J 0
(-3950 12350);
DISPLAY 0.787234 (-3950 12350);
FORCEPROP 1 LAST TOLERANCE 20%
J 0
(-3950 12400);
DISPLAY 0.787234 (-3950 12400);
FORCEPROP 1 LAST VOLTAGE 16V
J 0
(-3950 12450);
DISPLAY 0.787234 (-3950 12450);
FORCEPROP 1 LAST VALUE 22UF
J 0
(-3950 12500);
DISPLAY 0.787234 (-3950 12500);
FORCEPROP 1 LAST PACK_TYPE C0805
J 0
(-3950 12250);
DISPLAY 0.787234 (-3950 12250);
FORCEPROP 1 LAST $LOCATION C535
J 0
(-3950 12550);
DISPLAY 0.978723 (-3950 12550);
FORCEPROP 1 LASTPIN (-4000 12550) $PN 1
J 0
(-3990 12530);
DISPLAY 0.787234 (-3990 12530);
PAINT MONO (-3990 12530);
FORCEPROP 1 LASTPIN (-4000 12350) $PN 2
J 0
(-3990 12330);
DISPLAY 0.787234 (-3990 12330);
PAINT MONO (-3990 12330);
FORCEPROP 1 LAST PATH I4
J 0
(-3950 12600);
DISPLAY 0.978723 (-3950 12600);
PAINT WHITE (-3950 12600);
DISPLAY INVISIBLE (-3950 12600);
FORCEPROP 2 LAST CDS_LIB pure_quanta
J 0
(-4000 12450);
PAINT MONO (-4000 12450);
DISPLAY INVISIBLE (-4000 12450);
FORCEPROP 0 LAST CDS_LOCATION C535
J 0
(-3950 12600);
DISPLAY 1.021277 (-3950 12600);
DISPLAY INVISIBLE (-3950 12600);
FORCEPROP 0 LAST $SEC 1
J 0
(-3950 12600);
DISPLAY 0.680851 (-3950 12600);
PAINT MONO (-3950 12600);
DISPLAY INVISIBLE (-3950 12600);
FORCEPROP 0 LAST CDS_SEC 1
J 0
(-3950 12600);
DISPLAY 1.021277 (-3950 12600);
DISPLAY INVISIBLE (-3950 12600);
FORCEADD Q_CAP..1
(-4475 12450);
FORCEPROP 1 LAST PART_NUMBER CH6223MEA01
J 0
(-4425 12300);
DISPLAY 0.787234 (-4425 12300);
DISPLAY INVISIBLE (-4425 12300);
FORCEPROP 1 LAST PACK_TYPE C0805
J 0
(-4425 12250);
DISPLAY 0.787234 (-4425 12250);
FORCEPROP 1 LAST TOLERANCE 20%
J 0
(-4425 12400);
DISPLAY 0.787234 (-4425 12400);
FORCEPROP 1 LAST VALUE 22UF
J 0
(-4425 12500);
DISPLAY 0.787234 (-4425 12500);
FORCEPROP 1 LAST VOLTAGE 16V
J 0
(-4425 12450);
DISPLAY 0.787234 (-4425 12450);
FORCEPROP 1 LAST MATERIAL X6S
J 0
(-4425 12350);
DISPLAY 0.787234 (-4425 12350);
FORCEPROP 1 LAST $LOCATION C513
J 0
(-4425 12550);
DISPLAY 0.787234 (-4425 12550);
FORCEPROP 1 LASTPIN (-4475 12550) $PN 1
J 0
(-4465 12530);
DISPLAY 0.787234 (-4465 12530);
PAINT MONO (-4465 12530);
FORCEPROP 1 LASTPIN (-4475 12350) $PN 2
J 0
(-4465 12330);
DISPLAY 0.787234 (-4465 12330);
PAINT MONO (-4465 12330);
FORCEPROP 1 LAST PATH I5
J 0
(-4425 12600);
DISPLAY 0.978723 (-4425 12600);
PAINT WHITE (-4425 12600);
DISPLAY INVISIBLE (-4425 12600);
FORCEPROP 2 LAST CDS_LIB pure_quanta
J 0
(-4475 12450);
PAINT MONO (-4475 12450);
DISPLAY INVISIBLE (-4475 12450);
FORCEPROP 0 LAST CDS_LOCATION C513
J 0
(-4425 12600);
DISPLAY 1.021277 (-4425 12600);
DISPLAY INVISIBLE (-4425 12600);
FORCEPROP 0 LAST $SEC 1
J 0
(-4425 12600);
DISPLAY 0.680851 (-4425 12600);
PAINT MONO (-4425 12600);
DISPLAY INVISIBLE (-4425 12600);
FORCEPROP 0 LAST CDS_SEC 1
J 0
(-4425 12600);
DISPLAY 1.021277 (-4425 12600);
DISPLAY INVISIBLE (-4425 12600);
FORCEADD UNIVERSAL_POWER..1
(-9200 13550);
FORCEPROP 3 LASTPIN (-9200 13500) SIG_NAME PGPPA_AUX\g
J 0
(-9190 13510);
DISPLAY 0.659574 (-9190 13510);
PAINT MONO (-9190 13510);
DISPLAY INVISIBLE (-9190 13510);
FORCEPROP 1 LAST HDL_POWER PGPPA_AUX
J 1
(-9200 13600);
DISPLAY 0.617021 (-9200 13600);
PAINT GREEN (-9200 13600);
FORCEPROP 2 LAST BOM_COST VR_SYSTEM 
J 0
(-9200 13650);
DISPLAY 0.680851 (-9200 13650);
DISPLAY INVISIBLE (-9200 13650);
FORCEPROP 1 LAST PATH I6
J 0
(-9150 13575);
DISPLAY 0.872340 (-9150 13575);
PAINT AQUA (-9150 13575);
DISPLAY INVISIBLE (-9150 13575);
FORCEPROP 2 LAST CDS_LIB logical_power
J 0
(-9200 13550);
PAINT MONO (-9200 13550);
DISPLAY INVISIBLE (-9200 13550);
FORCEADD Q_RES..2
(-9200 13250);
FORCEPROP 1 LAST PART_NUMBER CS31002FB08
J 0
(-9160 13125);
DISPLAY 0.638298 (-9160 13125);
DISPLAY INVISIBLE (-9160 13125);
FORCEPROP 1 LAST WATTAGE 1/16W
J 0
(-9160 13225);
DISPLAY 0.638298 (-9160 13225);
FORCEPROP 1 LAST TOLERANCE 1%
J 0
(-9155 13275);
DISPLAY 0.638298 (-9155 13275);
FORCEPROP 1 LAST VALUE 10K
J 0
(-9155 13325);
DISPLAY 0.638298 (-9155 13325);
FORCEPROP 1 LAST PACK_TYPE 0402LF
J 0
(-9160 13075);
DISPLAY 0.638298 (-9160 13075);
FORCEPROP 1 LAST MATERIAL EMPTY
J 0
(-9160 13175);
DISPLAY 0.638298 (-9160 13175);
PAINT RED (-9160 13175);
FORCEPROP 1 LAST $LOCATION R1763
J 0
(-9155 13375);
DISPLAY 0.638298 (-9155 13375);
FORCEPROP 1 LASTPIN (-9200 13350) $PN 1
J 0
(-9195 13312);
DISPLAY 0.787234 (-9195 13312);
PAINT MONO (-9195 13312);
FORCEPROP 1 LASTPIN (-9200 13150) $PN 2
J 0
(-9195 13160);
DISPLAY 0.787234 (-9195 13160);
PAINT MONO (-9195 13160);
FORCEPROP 2 LAST CDS_LIB pure_quanta
J 0
(-9200 13250);
DISPLAY INVISIBLE (-9200 13250);
FORCEPROP 1 LAST PATH I7
J 0
(-9150 13425);
DISPLAY 0.978723 (-9150 13425);
PAINT WHITE (-9150 13425);
DISPLAY INVISIBLE (-9150 13425);
FORCEPROP 2 LAST CDS_LOCATION R1763
J 0
(-9150 13475);
DISPLAY 1.021277 (-9150 13475);
DISPLAY INVISIBLE (-9150 13475);
FORCEPROP 0 LAST $SEC 1
J 0
(-9150 13425);
DISPLAY 0.680851 (-9150 13425);
PAINT MONO (-9150 13425);
DISPLAY INVISIBLE (-9150 13425);
FORCEPROP 2 LAST CDS_SEC 1
J 0
(-9150 13475);
DISPLAY 1.021277 (-9150 13475);
DISPLAY INVISIBLE (-9150 13475);
FORCEADD Q_RES..2
(-9200 12650);
FORCEPROP 1 LAST PART_NUMBER CS21002FB06
J 0
(-9160 12525);
DISPLAY 0.638298 (-9160 12525);
DISPLAY INVISIBLE (-9160 12525);
FORCEPROP 1 LAST MATERIAL EMPTY
J 0
(-9160 12575);
DISPLAY 0.638298 (-9160 12575);
PAINT RED (-9160 12575);
FORCEPROP 1 LAST VALUE 1K
J 0
(-9155 12725);
DISPLAY 0.638298 (-9155 12725);
FORCEPROP 1 LAST WATTAGE 1/16W
J 0
(-9160 12625);
DISPLAY 0.638298 (-9160 12625);
FORCEPROP 1 LAST TOLERANCE 1%
J 0
(-9155 12675);
DISPLAY 0.638298 (-9155 12675);
FORCEPROP 1 LAST PACK_TYPE 0402LF
J 0
(-9160 12475);
DISPLAY 0.638298 (-9160 12475);
FORCEPROP 1 LAST $LOCATION R1764
J 0
(-9155 12775);
DISPLAY 0.638298 (-9155 12775);
FORCEPROP 1 LASTPIN (-9200 12750) $PN 1
J 0
(-9195 12712);
DISPLAY 0.787234 (-9195 12712);
PAINT MONO (-9195 12712);
FORCEPROP 1 LASTPIN (-9200 12550) $PN 2
J 0
(-9195 12560);
DISPLAY 0.787234 (-9195 12560);
PAINT MONO (-9195 12560);
FORCEPROP 2 LAST CDS_LIB pure_quanta
J 0
(-9200 12650);
DISPLAY INVISIBLE (-9200 12650);
FORCEPROP 1 LAST PATH I8
J 0
(-9150 12825);
DISPLAY 0.978723 (-9150 12825);
PAINT WHITE (-9150 12825);
DISPLAY INVISIBLE (-9150 12825);
FORCEPROP 2 LAST CDS_LOCATION R1764
J 0
(-9150 12875);
DISPLAY 1.021277 (-9150 12875);
DISPLAY INVISIBLE (-9150 12875);
FORCEPROP 0 LAST $SEC 1
J 0
(-9150 12825);
DISPLAY 0.680851 (-9150 12825);
PAINT MONO (-9150 12825);
DISPLAY INVISIBLE (-9150 12825);
FORCEPROP 2 LAST CDS_SEC 1
J 0
(-9150 12875);
DISPLAY 1.021277 (-9150 12875);
DISPLAY INVISIBLE (-9150 12875);
FORCEADD UNIVERSAL_GND..1
(-9200 12300);
FORCEPROP 3 LASTPIN (-9200 12350) SIG_NAME GND\g
J 0
(-9190 12360);
DISPLAY 0.659574 (-9190 12360);
PAINT MONO (-9190 12360);
DISPLAY INVISIBLE (-9190 12360);
FORCEPROP 1 LAST PATH I9
J 0
(-9125 12300);
DISPLAY 0.872340 (-9125 12300);
PAINT AQUA (-9125 12300);
DISPLAY INVISIBLE (-9125 12300);
FORCEPROP 1 LAST HDL_POWER GND
J 1
(-9175 12225);
DISPLAY 0.872340 (-9175 12225);
PAINT GREEN (-9175 12225);
DISPLAY INVISIBLE (-9175 12225);
FORCEPROP 2 LAST CDS_LIB logical_power
J 0
(-9200 12300);
PAINT MONO (-9200 12300);
DISPLAY INVISIBLE (-9200 12300);
FORCEADD QUANTA_TITLE_BLOCK_C..1
(-1550 9400);
FORCEPROP 0 LAST CDS_CON_LAST_MODIFIED Fri Aug 25 14:04:28 2023
J 0
(-3435 9415);
DISPLAY INVISIBLE (-3435 9415);
FORCEPROP 1 LAST CUSTOM_TXT_CDS <CON_LAST_MODIFIED>
J 0
(-3435 9415);
DISPLAY 0.978723 (-3435 9415);
FORCEPROP 2 LAST CUSTOM_TXT_CDS <XR_PAGE_TITLE>
J 0
(-9440 14650);
DISPLAY 0.638298 (-9440 14650);
PAINT PINK (-9440 14650);
DISPLAY INVISIBLE (-9440 14650);
FORCEPROP 1 LAST CUSTOM_TXT_CDS <NAME_2>
J 0
(-4725 9450);
FORCEPROP 1 LAST CUSTOM_TXT_CDS <NAME_1>
J 0
(-4725 9575);
FORCEPROP 1 LAST CUSTOM_TXT_CDS <Q_NUMBER>
J 0
(-2953 9503);
DISPLAY 1.212766 (-2953 9503);
FORCEPROP 1 LAST CUSTOM_TXT_CDS <Q_PROJ>
J 0
(-3932 9502);
DISPLAY 1.212766 (-3932 9502);
FORCEPROP 1 LAST CUSTOM_TXT_CDS <Q_REV>
J 0
(-1734 9503);
DISPLAY 1.212766 (-1734 9503);
FORCEPROP 1 LAST CUSTOM_TXT_CDS <CON_PAGE_NUM> OF <CON_TOTAL_PAGES>
J 0
(-1996 9418);
DISPLAY 0.978723 (-1996 9418);
FORCEPROP 1 LAST Q_TITLE PGPPA_AUX
J 0
(-10891 9426);
DISPLAY 2.446809 (-10891 9426);
PAINT GREEN (-10891 9426);
FORCEPROP 1 LAST Q_DEPT 
J 1
(-5313 9449);
DISPLAY 1.957447 (-5313 9449);
PAINT GREEN (-5313 9449);
FORCEPROP 2 LAST CDS_XR_PAGE_TITLE CR-257 : @S9S_MB_2U_LIB.S9S_MB_2U(SCH_1):PAGE257
J 0
(-9440 14650);
DISPLAY 0.638298 (-9440 14650);
PAINT PINK (-9440 14650);
DISPLAY INVISIBLE (-9440 14650);
FORCEPROP 2 LAST BOM_COST VR_SYSTEM 
J 0
(-4725 9600);
DISPLAY 0.680851 (-4725 9600);
DISPLAY INVISIBLE (-4725 9600);
FORCEPROP 1 LAST COMMENT_BODY TRUE
J 0
(-1538 9387);
DISPLAY 0.978723 (-1538 9387);
PAINT GREEN (-1538 9387);
DISPLAY INVISIBLE (-1538 9387);
FORCEPROP 1 LAST CDS_LMAN_SYM_OUTLINE -9475,6775,100,-125
J 0
(-1550 9400);
DISPLAY 0.468085 (-1550 9400);
PAINT GREEN (-1550 9400);
DISPLAY INVISIBLE (-1550 9400);
FORCEPROP 2 LAST CDS_LIB pure_quanta
J 0
(-1550 9400);
DISPLAY INVISIBLE (-1550 9400);
FORCEPROP 2 LAST PAGE_BORDER TRUE
J 0
(-9440 14650);
DISPLAY 0.638298 (-9440 14650);
PAINT PINK (-9440 14650);
DISPLAY INVISIBLE (-9440 14650);
FORCEADD DESIGN_NOTE..1
(-10100 14100);
FORCEPROP 0 LAST L1 1: FOR LPC
J 0
(-10275 13900);
DISPLAY 0.680851 (-10275 13900);
PAINT SKYBLUE (-10275 13900);
FORCEPROP 0 LAST L2 LPC_ESPI_SEL
J 0
(-10275 13975);
DISPLAY 0.680851 (-10275 13975);
PAINT SKYBLUE (-10275 13975);
FORCEPROP 0 LAST L3 0: FOR ESPI(DEFAULT),PU 10KOHM AT SCM BOARD.
J 0
(-10275 13825);
DISPLAY 0.680851 (-10275 13825);
PAINT SKYBLUE (-10275 13825);
FORCEPROP 2 LAST BOM_COST VR_SYSTEM 
J 0
(-10275 14025);
DISPLAY 0.680851 (-10275 14025);
DISPLAY INVISIBLE (-10275 14025);
FORCEPROP 1 LAST COMMENT_BODY TRUE
J 0
(-10075 14200);
DISPLAY 0.978723 (-10075 14200);
DISPLAY INVISIBLE (-10075 14200);
FORCEPROP 2 LAST CDS_LIB logical_power
J 0
(-10100 14100);
DISPLAY INVISIBLE (-10100 14100);
FORCEADD DESIGN_NOTE..1
(-10250 12250);
FORCEPROP 0 LAST L2 EMPTY R1763, IT ALREADY PU AT SCM BOARD
J 0
(-10425 12125);
DISPLAY 0.680851 (-10425 12125);
PAINT SKYBLUE (-10425 12125);
FORCEPROP 2 LAST CDS_LIB logical_power
J 0
(-10250 12250);
DISPLAY INVISIBLE (-10250 12250);
FORCEPROP 2 LAST BOM_COST VR_SYSTEM 
J 0
(-10425 12175);
DISPLAY 0.680851 (-10425 12175);
DISPLAY INVISIBLE (-10425 12175);
FORCEPROP 1 LAST COMMENT_BODY TRUE
J 0
(-10225 12350);
DISPLAY 0.978723 (-10225 12350);
DISPLAY INVISIBLE (-10225 12350);
FORCEADD DNS..1
(-4675 11775);
PAINT RED (-4675 11775);
FORCEPROP 1 LAST COMMENT_BODY TRUE
R 1
J 0
(-4600 11550);
DISPLAY 0.872340 (-4600 11550);
PAINT GREEN (-4600 11550);
DISPLAY INVISIBLE (-4600 11550);
FORCEPROP 2 LAST BOM_COST VR_SYSTEM 
J 0
(-4850 11950);
DISPLAY 0.680851 (-4850 11950);
DISPLAY INVISIBLE (-4850 11950);
FORCEPROP 2 LAST CDS_LIB mstr_misc
J 0
(-4675 11775);
DISPLAY INVISIBLE (-4675 11775);
FORCEADD DESIGN_NOTE..1
(-3225 13250);
FORCEPROP 0 LAST L2 PGPPA_AUX
J 0
(-3400 13125);
DISPLAY 0.680851 (-3400 13125);
PAINT SKYBLUE (-3400 13125);
FORCEPROP 0 LAST L3 = P1V8_AUX FOR ESPI
J 0
(-3400 12975);
DISPLAY 0.680851 (-3400 12975);
PAINT SKYBLUE (-3400 12975);
FORCEPROP 0 LAST L1 = P3V3_AUX FOR LPC
J 0
(-3400 13050);
DISPLAY 0.680851 (-3400 13050);
PAINT SKYBLUE (-3400 13050);
FORCEPROP 1 LAST COMMENT_BODY TRUE
J 0
(-3200 13350);
DISPLAY 0.978723 (-3200 13350);
DISPLAY INVISIBLE (-3200 13350);
FORCEPROP 2 LAST BOM_COST VR_SYSTEM 
J 0
(-3400 13175);
DISPLAY 0.680851 (-3400 13175);
DISPLAY INVISIBLE (-3400 13175);
FORCEPROP 2 LAST CDS_LIB logical_power
J 0
(-3225 13250);
DISPLAY INVISIBLE (-3225 13250);
FORCEADD DESIGN_NOTE..1
(-3225 12725);
FORCEPROP 0 LAST L1 ESPI IS BACKUP
J 0
(-3400 12525);
DISPLAY 0.680851 (-3400 12525);
PAINT SKYBLUE (-3400 12525);
FORCEPROP 0 LAST L2 LPC PRIMARY
J 0
(-3400 12600);
DISPLAY 0.680851 (-3400 12600);
PAINT SKYBLUE (-3400 12600);
FORCEPROP 2 LAST CDS_LIB logical_power
J 0
(-3225 12725);
DISPLAY INVISIBLE (-3225 12725);
FORCEPROP 1 LAST COMMENT_BODY TRUE
J 0
(-3200 12825);
DISPLAY 0.978723 (-3200 12825);
DISPLAY INVISIBLE (-3200 12825);
FORCEPROP 2 LAST BOM_COST VR_SYSTEM 
J 0
(-3400 12650);
DISPLAY 0.680851 (-3400 12650);
DISPLAY INVISIBLE (-3400 12650);
FORCEADD DESIGN_NOTE..1
(-3225 12225);
FORCEPROP 0 LAST L1 P1V8 : 0.2A
J 0
(-3400 12025);
DISPLAY 0.851064 (-3400 12025);
PAINT SKYBLUE (-3400 12025);
FORCEPROP 0 LAST L3 P3V3 : 0.2A
J 0
(-3400 11975);
DISPLAY 0.851064 (-3400 11975);
PAINT SKYBLUE (-3400 11975);
FORCEPROP 0 LAST L2 PDG PGPPA TDC
J 0
(-3400 12100);
DISPLAY 0.851064 (-3400 12100);
PAINT SKYBLUE (-3400 12100);
FORCEPROP 2 LAST CDS_LIB logical_power
J 0
(-3225 12225);
DISPLAY INVISIBLE (-3225 12225);
FORCEPROP 1 LAST COMMENT_BODY TRUE
J 0
(-3200 12325);
DISPLAY 0.978723 (-3200 12325);
DISPLAY INVISIBLE (-3200 12325);
FORCEPROP 2 LAST BOM_COST VR_SYSTEM 
J 0
(-3400 12150);
DISPLAY 0.680851 (-3400 12150);
DISPLAY INVISIBLE (-3400 12150);
FORCEADD DNS..1
(-9200 13225);
PAINT RED (-9200 13225);
FORCEPROP 1 LAST COMMENT_BODY TRUE
R 1
J 0
(-9125 13000);
DISPLAY 0.872340 (-9125 13000);
PAINT GREEN (-9125 13000);
DISPLAY INVISIBLE (-9125 13000);
FORCEPROP 2 LAST BOM_COST VR_SYSTEM 
J 0
(-9375 13400);
DISPLAY 0.680851 (-9375 13400);
DISPLAY INVISIBLE (-9375 13400);
FORCEPROP 2 LAST CDS_LIB mstr_misc
J 0
(-9200 13225);
PAINT MONO (-9200 13225);
DISPLAY INVISIBLE (-9200 13225);
FORCEADD DNS..1
(-9200 12600);
PAINT RED (-9200 12600);
FORCEPROP 2 LAST CDS_LIB mstr_misc
J 0
(-9200 12600);
DISPLAY INVISIBLE (-9200 12600);
FORCEPROP 2 LAST BOM_COST VR_SYSTEM 
J 0
(-9375 12775);
DISPLAY 0.680851 (-9375 12775);
DISPLAY INVISIBLE (-9375 12775);
FORCEPROP 1 LAST COMMENT_BODY TRUE
R 1
J 0
(-9125 12375);
DISPLAY 0.872340 (-9125 12375);
PAINT GREEN (-9125 12375);
DISPLAY INVISIBLE (-9125 12375);
WIRE 16 -1 (-8500 13500)(-8500 13350);
WIRE 16 -1 (-9200 13500)(-9200 13350);
WIRE 16 -1 (-4000 12775)(-4000 12625);
WIRE 16 -1 (-4675 13725)(-4675 14175);
WIRE 16 -1 (-4125 11675)(-4125 11375);
WIRE 16 -1 (-9200 12550)(-9200 12350);
WIRE 16 -1 (-8500 12600)(-8500 12400);
WIRE 16 -1 (-4000 12225)(-4000 12175);
WIRE 16 -1 (-4475 12225)(-4000 12225);
WIRE 16 -1 (-4000 12350)(-4000 12225);
WIRE 16 2175 (-8650 13675)(-6025 13675);
WIRE 16 2175 (-6025 13675)(-6025 12125);
WIRE 16 2175 (-8650 13675)(-8650 12125);
WIRE 16 2175 (-8650 12125)(-6025 12125);
WIRE 16 2175 (-9400 12425)(-8825 12425);
WIRE 16 2175 (-8825 12825)(-8825 12425);
WIRE 16 2175 (-9400 12825)(-9400 12425);
WIRE 16 2175 (-9400 12825)(-8825 12825);
WIRE 16 -1 (-10150 12950)(-9200 12950);
FORCEPROP 0 LAST CDS_PHYS_NET_NAME FM_LPC_ESPI_SEL
J 0
(-10135 12992);
PAINT MONO (-10135 12992);
DISPLAY INVISIBLE (-10135 12992);
FORCEPROP 2 LAST SIG_NAME FM_LPC_ESPI_SEL
J 0
(-9985 12960);
DISPLAY 0.553191 (-9985 12960);
PAINT WHITE (-9985 12960);
WIRE 16 -1 (-9200 12950)(-9200 12750);
WIRE 16 -1 (-9200 12950)(-9200 13150);
WIRE 16 -1 (-8500 12950)(-9200 12950);
WIRE 16 -1 (-8500 13150)(-8500 12950);
WIRE 16 -1 (-8500 12900)(-8500 12950);
WIRE 16 -1 (-7475 12700)(-8350 12700);
FORCEPROP 0 LAST CDS_PHYS_NET_NAME FM_ESPI_PLD_R_EN_BUF
J 0
(-8160 12748);
PAINT MONO (-8160 12748);
DISPLAY INVISIBLE (-8160 12748);
FORCEPROP 2 LAST SIG_NAME FM_ESPI_PLD_R_EN_BUF_R
J 0
(-8335 12710);
DISPLAY 0.638298 (-8335 12710);
PAINT WHITE (-8335 12710);
WIRE 16 -1 (-6450 12700)(-7275 12700);
FORCEPROP 0 LAST CDS_PHYS_NET_NAME FM_ESPI_PLD_R_EN_BUF
J 0
(-7085 12748);
PAINT MONO (-7085 12748);
DISPLAY INVISIBLE (-7085 12748);
FORCEPROP 2 LAST SIG_NAME FM_ESPI_PLD_R_EN_BUF
J 0
(-7060 12710);
DISPLAY 0.638298 (-7060 12710);
PAINT WHITE (-7060 12710);
WIRE 16 -1 (-4675 12625)(-4675 11900);
WIRE 16 -1 (-4675 12625)(-4675 13525);
WIRE 16 -1 (-4475 12625)(-4675 12625);
WIRE 16 -1 (-4475 12550)(-4475 12625);
WIRE 16 -1 (-4475 12625)(-4000 12625);
WIRE 16 -1 (-4000 12625)(-4000 12550);
WIRE 16 -1 (-4475 12350)(-4475 12225);
WIRE 16 -1 (-4675 11375)(-4125 11375);
WIRE 16 -1 (-4675 11700)(-4675 11375);
DOT 1 (-8500 12950);
DOT 1 (-9200 12950);
DOT 1 (-4000 12225);
DOT 1 (-4675 12625);
DOT 1 (-4475 12625);
DOT 1 (-4000 12625);
FORCENOTE
20211201 CONTROL WITH FPGA
(-8475 11975) 0;
DISPLAY LEFT (-8475 11975);
DISPLAY 1.595745 (-8475 11975);
PAINT PINK (-8475 11975);
FORCENOTE
ID (TA/25 DEG) : 4A
(-5625 11550) 0;
DISPLAY LEFT (-5625 11550);
DISPLAY 1.021277 (-5625 11550);
PAINT WHITE (-5625 11550);
FORCENOTE
ID (TA/25 DEG) : 0.3A
(-4400 14175) 0;
DISPLAY LEFT (-4400 14175);
DISPLAY 1.595745 (-4400 14175);
PAINT WHITE (-4400 14175);
QUIT
